# S9S_MB_2U (Grand Teton) — schematic netlist excerpt (pin names and nets, part order shuffled) for the footprints in the layout excerpt that follows; sources: Cadence DE-HDL packaged netlist, KiCad conversion of 03242023_DA0F0TMBIJ0_F0T_Motherboard_J_brd_V01_OCP.brd

PC536_P1_3  Q_CAP  22UF 16V 20% X6S  pkg C0805  page 286 : A = SW_P12V_PVCCIN_CPU1_FLT ; B = GND
C2296  Q_CAP  0.1UF 25V 10% EMPTY  pkg 0402  page 245 : A = FM_FAN_PWR_EN_R ; B = GND
R2384  Q_RES  10K 1% EMPTY  pkg 0402LF  page 300 : A = P3V3_AUX ; B = FM_PVNN_MAIN_CPU1_EN

(kicad_pcb
	(version 20260206)
	(generator "pcbnew")
	(generator_version "10.0")
	(general
		(thickness 1.6)
		(legacy_teardrops no)
	)
	(paper "A4")
	(title_block
		(title "03242023_DA0F0TMBIJ0_F0T_Motherboard_J_brd_V01_OCP.brd")
		(comment 1 "Grand Teton / footprints 4514-4516 of 6105")
	)
	(layers
		(0 "F.Cu" signal "TOP")
		(4 "In1.Cu" signal "GND")
		(6 "In2.Cu" signal "IN1")
		(8 "In3.Cu" signal "GND1")
		(10 "In4.Cu" signal "IN2")
		(12 "In5.Cu" signal "GND2")
		(14 "In6.Cu" signal "IN3")
		(16 "In7.Cu" signal "GND3")
		(18 "In8.Cu" signal "VCC")
		(20 "In9.Cu" signal "VCC1")
		(22 "In10.Cu" signal "GND4")
		(24 "In11.Cu" signal "IN4")
		(26 "In12.Cu" signal "GND5")
		(28 "In13.Cu" signal "IN5")
		(30 "In14.Cu" signal "GND6")
		(32 "In15.Cu" signal "IN6")
		(34 "In16.Cu" signal "GND7")
		(2 "B.Cu" signal "BOTTOM")
		(9 "F.Adhes" user "F.Adhesive")
		(11 "B.Adhes" user "B.Adhesive")
		(13 "F.Paste" user "Package Geometry/Pastemask Top")
		(15 "B.Paste" user "Package Geometry/Pastemask Bottom")
		(5 "F.SilkS" user "Ref Des/Silkscreen Top")
		(7 "B.SilkS" user "Ref Des/Silkscreen Bottom")
		(1 "F.Mask" user "Board Geometry/Soldermask Top")
		(3 "B.Mask" user "Board Geometry/Soldermask Bottom")
		(17 "Dwgs.User" user "User.Drawings")
		(19 "Cmts.User" user "User.Comments")
		(21 "Eco1.User" user "User.Eco1")
		(23 "Eco2.User" user "User.Eco2")
		(25 "Edge.Cuts" user "Board Geometry/Outline")
		(27 "Margin" user)
		(31 "F.CrtYd" user "Package Geometry/Place Bound Top")
		(29 "B.CrtYd" user "Package Geometry/Place Bound Bottom")
		(35 "F.Fab" user "Ref Des/Assembly Top")
		(33 "B.Fab" user "Ref Des/Assembly Bottom")
	)
	(footprint ""
		(layer "B.Cu")
		(at 18.613374 -176.431194 90)
		(property "Reference" "R2384"
			(at 0 0 90)
			(layer "B.SilkS")
			(hide yes)
			(effects
				(font
					(size 1.27 1.27)
				)
				(justify mirror)
			)
		)
		(property "Value" ""
			(at 0 0 90)
			(layer "B.Fab")
			(effects
				(font
					(size 1.27 1.27)
				)
				(justify mirror)
			)
		)
		(duplicate_pad_numbers_are_jumpers no)
		(fp_line
			(start 0.7874 -0.4064)
			(end -0.7874 -0.4064)
			(stroke
				(width 0.1524)
				(type default)
			)
			(layer "B.SilkS")
		)
		(fp_line
			(start -0.7874 -0.4064)
			(end -0.7874 0.4064)
			(stroke
				(width 0.1524)
				(type default)
			)
			(layer "B.SilkS")
		)
		(fp_line
			(start 0.7874 0.4064)
			(end 0.7874 -0.4064)
			(stroke
				(width 0.1524)
				(type default)
			)
			(layer "B.SilkS")
		)
		(fp_line
			(start -0.7874 0.4064)
			(end 0.7874 0.4064)
			(stroke
				(width 0.1524)
				(type default)
			)
			(layer "B.SilkS")
		)
		(fp_line
			(start 0.67945 -0.305054)
			(end 0.12065 -0.305054)
			(stroke
				(width 0.1)
				(type default)
			)
			(layer "B.Fab")
		)
		(fp_line
			(start 0.12065 -0.305054)
			(end 0.12065 -0.2794)
			(stroke
				(width 0.1)
				(type default)
			)
			(layer "B.Fab")
		)
		(fp_line
			(start -0.12065 -0.3048)
			(end -0.67945 -0.3048)
			(stroke
				(width 0.1)
				(type default)
			)
			(layer "B.Fab")
		)
		(fp_line
			(start -0.67945 -0.3048)
			(end -0.67945 0.3048)
			(stroke
				(width 0.1)
				(type default)
			)
			(layer "B.Fab")
		)
		(fp_line
			(start 0.12065 -0.2794)
			(end -0.12065 -0.2794)
			(stroke
				(width 0.1)
				(type default)
			)
			(layer "B.Fab")
		)
		(fp_line
			(start -0.12065 -0.2794)
			(end -0.12065 -0.3048)
			(stroke
				(width 0.1)
				(type default)
			)
			(layer "B.Fab")
		)
		(fp_line
			(start 0.12065 0.2794)
			(end 0.12065 0.3048)
			(stroke
				(width 0.1)
				(type default)
			)
			(layer "B.Fab")
		)
		(fp_line
			(start -0.120396 0.2794)
			(end 0.12065 0.2794)
			(stroke
				(width 0.1)
				(type default)
			)
			(layer "B.Fab")
		)
		(fp_line
			(start 0.67945 0.3048)
			(end 0.67945 -0.305054)
			(stroke
				(width 0.1)
				(type default)
			)
			(layer "B.Fab")
		)
		(fp_line
			(start 0.12065 0.3048)
			(end 0.67945 0.3048)
			(stroke
				(width 0.1)
				(type default)
			)
			(layer "B.Fab")
		)
		(fp_line
			(start -0.120396 0.3048)
			(end -0.120396 0.2794)
			(stroke
				(width 0.1)
				(type default)
			)
			(layer "B.Fab")
		)
		(fp_line
			(start -0.67945 0.3048)
			(end -0.120396 0.3048)
			(stroke
				(width 0.1)
				(type default)
			)
			(layer "B.Fab")
		)
		(pad "1" smd circle
			(at 0.40005 0 270)
			(size 0 0)
			(layers "B.Cu" "B.Mask" "B.Paste")
			(net "P3V3_AUX")
		)
		(pad "2" smd circle
			(at -0.40005 0 270)
			(size 0 0)
			(layers "B.Cu" "B.Mask" "B.Paste")
			(net "FM_PVNN_MAIN_CPU1_EN")
		)
	)
	(footprint ""
		(layer "B.Cu")
		(at 240.3094 -422.9862 90)
		(property "Reference" "C2296"
			(at 0 0 90)
			(layer "B.SilkS")
			(hide yes)
			(effects
				(font
					(size 1.27 1.27)
				)
				(justify mirror)
			)
		)
		(property "Value" ""
			(at 0 0 90)
			(layer "B.Fab")
			(effects
				(font
					(size 1.27 1.27)
				)
				(justify mirror)
			)
		)
		(duplicate_pad_numbers_are_jumpers no)
		(fp_line
			(start 0.7874 -0.4064)
			(end -0.7874 -0.4064)
			(stroke
				(width 0.1524)
				(type default)
			)
			(layer "B.SilkS")
		)
		(fp_line
			(start -0.7874 -0.4064)
			(end -0.7874 0.4064)
			(stroke
				(width 0.1524)
				(type default)
			)
			(layer "B.SilkS")
		)
		(fp_line
			(start 0.7874 0.4064)
			(end 0.7874 -0.4064)
			(stroke
				(width 0.1524)
				(type default)
			)
			(layer "B.SilkS")
		)
		(fp_line
			(start -0.7874 0.4064)
			(end 0.7874 0.4064)
			(stroke
				(width 0.1524)
				(type default)
			)
			(layer "B.SilkS")
		)
		(fp_line
			(start 0.67945 -0.305054)
			(end 0.12065 -0.305054)
			(stroke
				(width 0.1)
				(type default)
			)
			(layer "B.Fab")
		)
		(fp_line
			(start 0.12065 -0.305054)
			(end 0.12065 -0.2794)
			(stroke
				(width 0.1)
				(type default)
			)
			(layer "B.Fab")
		)
		(fp_line
			(start -0.12065 -0.3048)
			(end -0.67945 -0.3048)
			(stroke
				(width 0.1)
				(type default)
			)
			(layer "B.Fab")
		)
		(fp_line
			(start -0.67945 -0.3048)
			(end -0.67945 0.3048)
			(stroke
				(width 0.1)
				(type default)
			)
			(layer "B.Fab")
		)
		(fp_line
			(start 0.12065 -0.2794)
			(end -0.12065 -0.2794)
			(stroke
				(width 0.1)
				(type default)
			)
			(layer "B.Fab")
		)
		(fp_line
			(start -0.12065 -0.2794)
			(end -0.12065 -0.3048)
			(stroke
				(width 0.1)
				(type default)
			)
			(layer "B.Fab")
		)
		(fp_line
			(start 0.12065 0.2794)
			(end 0.12065 0.3048)
			(stroke
				(width 0.1)
				(type default)
			)
			(layer "B.Fab")
		)
		(fp_line
			(start -0.120396 0.2794)
			(end 0.12065 0.2794)
			(stroke
				(width 0.1)
				(type default)
			)
			(layer "B.Fab")
		)
		(fp_line
			(start 0.67945 0.3048)
			(end 0.67945 -0.305054)
			(stroke
				(width 0.1)
				(type default)
			)
			(layer "B.Fab")
		)
		(fp_line
			(start 0.12065 0.3048)
			(end 0.67945 0.3048)
			(stroke
				(width 0.1)
				(type default)
			)
			(layer "B.Fab")
		)
		(fp_line
			(start -0.120396 0.3048)
			(end -0.120396 0.2794)
			(stroke
				(width 0.1)
				(type default)
			)
			(layer "B.Fab")
		)
		(fp_line
			(start -0.67945 0.3048)
			(end -0.120396 0.3048)
			(stroke
				(width 0.1)
				(type default)
			)
			(layer "B.Fab")
		)
		(pad "1" smd circle
			(at 0.40005 0 270)
			(size 0 0)
			(layers "B.Cu" "B.Mask" "B.Paste")
			(net "FM_FAN_PWR_EN_R")
		)
		(pad "2" smd circle
			(at -0.40005 0 270)
			(size 0 0)
			(layers "B.Cu" "B.Mask" "B.Paste")
			(net "GND")
		)
	)
	(footprint ""
		(layer "B.Cu")
		(at 114.440462 -333.73568 90)
		(property "Reference" "PC536_P1_3"
			(at 0 0 90)
			(layer "B.SilkS")
			(hide yes)
			(effects
				(font
					(size 1.27 1.27)
				)
				(justify mirror)
			)
		)
		(property "Value" ""
			(at 0 0 90)
			(layer "B.Fab")
			(effects
				(font
					(size 1.27 1.27)
				)
				(justify mirror)
			)
		)
		(duplicate_pad_numbers_are_jumpers no)
		(fp_line
			(start 1.524 -0.762)
			(end -1.524 -0.762)
			(stroke
				(width 0.1524)
				(type default)
			)
			(layer "B.SilkS")
		)
		(fp_line
			(start -1.524 -0.762)
			(end -1.524 0.762)
			(stroke
				(width 0.1524)
				(type default)
			)
			(layer "B.SilkS")
		)
		(fp_line
			(start 1.524 0.762)
			(end 1.524 -0.762)
			(stroke
				(width 0.1524)
				(type default)
			)
			(layer "B.SilkS")
		)
		(fp_line
			(start -1.524 0.762)
			(end 1.524 0.762)
			(stroke
				(width 0.1524)
				(type default)
			)
			(layer "B.SilkS")
		)
		(fp_line
			(start 1.1049 -0.724916)
			(end 1.1049 0.724916)
			(stroke
				(width 0.1)
				(type default)
			)
			(layer "B.Fab")
		)
		(fp_line
			(start -1.1049 -0.724916)
			(end 1.1049 -0.724916)
			(stroke
				(width 0.1)
				(type default)
			)
			(layer "B.Fab")
		)
		(fp_line
			(start 1.1049 0.724916)
			(end -1.1049 0.724916)
			(stroke
				(width 0.1)
				(type default)
			)
			(layer "B.Fab")
		)
		(fp_line
			(start -1.1049 0.724916)
			(end -1.1049 -0.724916)
			(stroke
				(width 0.1)
				(type default)
			)
			(layer "B.Fab")
		)
		(pad "1" smd rect
			(at 0.889 0 90)
			(size 1.016 1.27)
			(layers "B.Cu" "B.Mask" "B.Paste")
			(net "SW_P12V_PVCCIN_CPU1_FLT")
		)
		(pad "2" smd rect
			(at -0.889 0 90)
			(size 1.016 1.27)
			(layers "B.Cu" "B.Mask" "B.Paste")
			(net "GND")
		)
	)
)
